FILE_TYPE = CONNECTIVITY;
{Allegro Design Entry HDL 17.2-2016 S066 (3851973) 4/6/2020}
"PAGE_NUMBER" = 523;
0"NC";
1"SG\g";
2"SG\g";
3"XP3R3V\g";
4"SG\g";
5"XP1R0V_FPGA_PG";
6"XP1R0V_PG";
7"XP1R0V_FPGA\g";
8"SG\g";
9"XP12R0V\g";
10"SG\g";
11"SG\g";
12"SG\g";
13"XP1R0V_AGND";
14"XP1R0V_SS";
15"XP1R0V_FB_R_TO_AGND";
16"UN$523$CAPACITOR$I31$2";
17"XP1R0V_SW";
18"VIN_XP1R0V";
19"UN$523$CAPACITOR$I7$1";
20"XP1R0V_RT";
21"XP1R0V_COMP";
22"UN$523$CAPACITOR$I9$1";
23"XP1R0V_AGND";
24"UN$523$CAPACITOR$I28$1";
25"XP3R3V_PG";
26"XP1R0V_BT";
27"UN$523$CAPACITOR$I24$1";
%"CAPACITOR"
"2","(-9250,3100)","0","passive","I10";
;
$LOCATION"C264"
CDS_LOCATION"C264"
$SEC"1"
CDS_SEC"1"
TOLERANCE"5%"
CDS_LIB"passive"
CDS_LMAN_SYM_OUTLINE"-50,0,50,-50"
CLS_PN"G104-0A180-FJ"
VALUE"18PF"
PACKAGE"0201"
VOLTAGE"25V";
"2"
$PN"2"13;
"1"
$PN"1"21;
%"RESISTOR"
"1","(-12300,2500)","0","passive","I104";
;
$LOCATION"R245"
CDS_LOCATION"R245"
$SEC"1"
CDS_SEC"1"
CLS_PN"G155-100R0-J0"
CDS_LMAN_SYM_OUTLINE"-50,50,100,-50"
CDS_LIB"passive"
TOLERANCE"-"
PACKAGE"0402"
VALUE"0OHM";
"1"
$PN"1"5;
"2"
$PN"2"6;
%"GND_SG"
"1","(-11600,2300)","0","cls","I106";
;
BODY_TYPE"PLUMBING"
CDS_LIB"cls"
CDS_LMAN_SYM_OUTLINE"0,0,100,-50"
HDL_POWER"SG";
"SGND"1;
%"RESISTOR"
"1","(-12600,4250)","0","passive","I109";
;
$LOCATION"R244"
CDS_LOCATION"R244"
$SEC"1"
CDS_SEC"1"
TOLERANCE"-"
CDS_LIB"passive"
CDS_LMAN_SYM_OUTLINE"-50,50,100,-50"
CLS_PN"G155-100R0-J0"
VALUE"0OHM"
PACKAGE"0402";
"1"
$PN"1"25;
"2"
$PN"2"19;
%"TPS54824RNVR_VQFN18"
"1","(-8650,4650)","0","stdlogic","I11";
;
$LOCATION"U26"
CDS_LOCATION"U26"
$SEC"1"
CDS_SEC"1"
CDS_LMAN_SYM_OUTLINE"0,0,1000,-1750"
CDS_LIB"stdlogic"
VALUE"TPS54424RNVT"
CLS_PN"G220-10657-01";
"PGOOD"
$PN"18"6;
"EN"
$PN"17"19;
"SS/TRK"
$PN"16"14;
"COMP"
$PN"15"21;
"FB"
$PN"14"15;
"RT/CLK"
$PN"13"20;
"AGND"
$PN"12"13;
"VIN_2"
$PN"11"18;
"PGND_6"
$PN"10"11;
"PGND_5"
$PN"9"11;
"PGND_4"
$PN"8"11;
"SW_2"
$PN"7"17;
"SW_1"
$PN"6"17;
"PGND_3"
$PN"5"11;
"PGND_2"
$PN"4"11;
"PGND_1"
$PN"3"11;
"VIN_1"
$PN"2"18;
"BOOT"
$PN"1"26;
%"CAPACITOR"
"2","(-11050,3350)","0","passive","I12";
;
$LOCATION"C259"
CDS_LOCATION"C259"
$SEC"1"
CDS_SEC"1"
CLS_PN"G105-0B223-EK"
CDS_LMAN_SYM_OUTLINE"-50,0,50,-50"
CDS_LIB"passive"
TOLERANCE"10%"
VALUE"0.022UF"
PACKAGE"0402"
VOLTAGE"25V";
"2"
$PN"2"13;
"1"
$PN"1"14;
%"CAPACITOR"
"2","(-11450,5200)","0","passive","I13";
;
$LOCATION"C257"
CDS_LOCATION"C257"
$SEC"1"
CDS_SEC"1"
TOLERANCE"20%"
CDS_LIB"passive"
CDS_LMAN_SYM_OUTLINE"-50,0,50,-50"
CLS_PN"G107-0F106-EM"
PACKAGE"0805"
VOLTAGE"25V"
VALUE"10UF";
"2"
$PN"2"12;
"1"
$PN"1"18;
%"CAPACITOR"
"2","(-11000,5200)","0","passive","I14";
;
$LOCATION"C260"
CDS_LOCATION"C260"
$SEC"1"
CDS_SEC"1"
TOLERANCE"20%"
CLS_PN"G107-0F106-EM"
CDS_LMAN_SYM_OUTLINE"-50,0,50,-50"
CDS_LIB"passive"
PACKAGE"0805"
VALUE"10UF"
VOLTAGE"25V";
"2"
$PN"2"12;
"1"
$PN"1"18;
%"RESISTOR"
"2","(-10500,3350)","0","passive","I15";
;
$LOCATION"R248"
CDS_LOCATION"R248"
$SEC"1"
CDS_SEC"1"
TOLERANCE"1%"
CLS_PN"G155-11003-01"
CDS_LIB"passive"
CDS_LMAN_SYM_OUTLINE"-50,50,50,-100"
PACKAGE"0402"
VALUE"100KOHM";
"1"
$PN"1"20;
"2"
$PN"2"13;
%"RESISTOR"
"2","(-9850,3250)","0","passive","I16";
;
$LOCATION"R249"
CDS_LOCATION"R249"
$SEC"1"
CDS_SEC"1"
CDS_LIB"passive"
CDS_LMAN_SYM_OUTLINE"-50,50,50,-100"
TOLERANCE"1%"
CLS_PN"G155-14701-01"
PACKAGE"0402"
VALUE"4.7KOHM";
"1"
$PN"1"21;
"2"
$PN"2"22;
%"CAPACITOR"
"2","(-10550,5200)","0","passive","I17";
;
$LOCATION"C261"
CDS_LOCATION"C261"
$SEC"1"
CDS_SEC"1"
TOLERANCE"10%"
CDS_LIB"passive"
CDS_LMAN_SYM_OUTLINE"-50,0,50,-50"
CLS_PN"G105-0B104-EK"
PACKAGE"0402"
VALUE"0.1UF"
VOLTAGE"25V";
"2"
$PN"2"12;
"1"
$PN"1"18;
%"GND_SG"
"1","(-10050,4650)","0","cls","I18";
;
BODY_TYPE"PLUMBING"
CDS_LIB"cls"
CDS_LMAN_SYM_OUTLINE"0,0,100,-50"
HDL_POWER"SG";
"SGND"12;
%"CAPACITOR"
"2","(-10000,5200)","0","passive","I19";
;
$LOCATION"C262"
CDS_LOCATION"C262"
$SEC"1"
CDS_SEC"1"
TOLERANCE"10%"
CLS_PN"G105-0B104-EK"
CDS_LMAN_SYM_OUTLINE"-50,0,50,-50"
CDS_LIB"passive"
PACKAGE"0402"
VOLTAGE"25V"
VALUE"0.1UF";
"2"
$PN"2"12;
"1"
$PN"1"18;
%"GND_SG"
"1","(-7250,2450)","0","cls","I20";
;
BODY_TYPE"PLUMBING"
CDS_LMAN_SYM_OUTLINE"0,0,100,-50"
CDS_LIB"cls"
HDL_POWER"SG";
"SGND"11;
%"RESISTOR"
"1","(-6300,4550)","0","passive","I23";
;
$LOCATION"R250"
CDS_LOCATION"R250"
$SEC"1"
CDS_SEC"1"
TOLERANCE"-"
CLS_PN"G155-100R0-J0"
CDS_LIB"passive"
CDS_LMAN_SYM_OUTLINE"-50,50,100,-50"
VALUE"0OHM"
PACKAGE"0402";
"1"
$PN"1"26;
"2"
$PN"2"27;
%"CAPACITOR"
"1","(-5400,4550)","0","passive","I24";
;
$LOCATION"C265"
CDS_LOCATION"C265"
$SEC"1"
CDS_SEC"1"
TOLERANCE"10%"
CDS_LMAN_SYM_OUTLINE"0,50,50,-50"
CDS_LIB"passive"
CLS_PN"G105-0B104-EK"
VOLTAGE"25V"
PACKAGE"0402"
VALUE"0.1UF";
"2"
$PN"2"17;
"1"
$PN"1"27;
%"INDUCTOR_2"
"1","(-4050,4350)","0","passive","I25";
;
$LOCATION"L5"
CDS_LOCATION"L5"
$SEC"1"
CDS_SEC"1"
CDS_LMAN_SYM_OUTLINE"-100,50,150,-50"
CDS_LIB"passive"
TOLERANCE"20%"
CLS_PN"G190-10418-01"
VALUE"1.0UH";
"1"
$PN"1"17;
"2"
$PN"2"7;
%"RESISTOR"
"1","(-3150,4700)","0","passive","I26";
;
$LOCATION"R253"
CDS_LOCATION"R253"
$SEC"1"
CDS_SEC"1"
TOLERANCE"1%"
CDS_LIB"passive"
CDS_LMAN_SYM_OUTLINE"-50,50,100,-50"
CLS_PN"G157-12R20-01"
PACKAGE"0805"
VALUE"2.2OHM"
NO_ASSY"TRUE";
"1"
$PN"1"16;
"2"
$PN"2"2;
%"CAPACITOR"
"2","(-3150,3550)","0","passive","I28";
;
$LOCATION"C267"
CDS_LOCATION"C267"
$SEC"1"
CDS_SEC"1"
TOLERANCE"10%"
CDS_LMAN_SYM_OUTLINE"-50,0,50,-50"
CDS_LIB"passive"
CLS_PN"G104-0B101-FK"
PACKAGE"0201"
VALUE"100PF";
"2"
$PN"2"15;
"1"
$PN"1"24;
%"RESISTOR"
"2","(-2550,3600)","0","passive","I29";
;
$LOCATION"R255"
CDS_LOCATION"R255"
$SEC"1"
CDS_SEC"1"
TOLERANCE"1%"
CLS_PN"G155-02262-01"
CDS_LMAN_SYM_OUTLINE"-50,50,50,-100"
CDS_LIB"passive"
VALUE"22.6K"
PACKAGE"0402";
"1"
$PN"1"24;
"2"
$PN"2"15;
%"RESISTOR"
"2","(-2550,4050)","0","passive","I30";
;
$LOCATION"R254"
CDS_LOCATION"R254"
$SEC"1"
CDS_SEC"1"
TOLERANCE"1%"
CLS_PN"G155-120R0-01"
CDS_LMAN_SYM_OUTLINE"-50,50,50,-100"
CDS_LIB"passive"
VALUE"20OHM"
PACKAGE"0402";
"1"
$PN"1"7;
"2"
$PN"2"24;
%"CAPACITOR"
"1","(-4150,4700)","0","passive","I31";
;
$LOCATION"C266"
CDS_LOCATION"C266"
$SEC"1"
CDS_SEC"1"
CLS_PN"G105-0A102-FJ"
CDS_LMAN_SYM_OUTLINE"0,50,50,-50"
CDS_LIB"passive"
TOLERANCE"5%"
PACKAGE"0402"
VALUE"1000PF"
NO_ASSY"TRUE"
VOLTAGE"50V";
"2"
$PN"2"16;
"1"
$PN"1"17;
%"GND_SG"
"1","(-2650,4550)","0","cls","I32";
;
BODY_TYPE"PLUMBING"
CDS_LIB"cls"
CDS_LMAN_SYM_OUTLINE"0,0,100,-50"
HDL_POWER"SG";
"SGND"2;
%"CAPACITOR"
"2","(-1850,4000)","0","passive","I33";
;
$LOCATION"C268"
CDS_LOCATION"C268"
$SEC"1"
CDS_SEC"1"
TOLERANCE"10%"
CDS_LMAN_SYM_OUTLINE"-50,0,50,-50"
CDS_LIB"passive"
CLS_PN"G105-0B104-CK"
VOLTAGE"10V"
PACKAGE"0402"
VALUE"0.1UF";
"2"
$PN"2"10;
"1"
$PN"1"7;
%"CAPACITOR"
"2","(-1350,4000)","0","passive","I34";
;
$LOCATION"C269"
CDS_LOCATION"C269"
$SEC"1"
CDS_SEC"1"
CLS_PN"G107-0F476-AM"
CDS_LMAN_SYM_OUTLINE"-50,0,50,-50"
CDS_LIB"passive"
TOLERANCE"20%"
VOLTAGE"4V"
PACKAGE"0805"
VALUE"47UF";
"2"
$PN"2"10;
"1"
$PN"1"7;
%"CAPACITOR"
"2","(-850,4000)","0","passive","I35";
;
$LOCATION"C270"
CDS_LOCATION"C270"
$SEC"1"
CDS_SEC"1"
TOLERANCE"20%"
CDS_LMAN_SYM_OUTLINE"-50,0,50,-50"
CDS_LIB"passive"
CLS_PN"G107-0F476-AM"
VOLTAGE"4V"
PACKAGE"0805"
VALUE"47UF";
"2"
$PN"2"10;
"1"
$PN"1"7;
%"GND_SG"
"1","(-450,3150)","0","cls","I36";
;
BODY_TYPE"PLUMBING"
CDS_LMAN_SYM_OUTLINE"0,0,100,-50"
CDS_LIB"cls"
HDL_POWER"SG";
"SGND"10;
%"CAPACITOR"
"2","(-400,4000)","0","passive","I37";
;
$LOCATION"C271"
CDS_LOCATION"C271"
$SEC"1"
CDS_SEC"1"
TOLERANCE"20%"
CDS_LIB"passive"
CDS_LMAN_SYM_OUTLINE"-50,0,50,-50"
CLS_PN"G107-0F476-AM"
VOLTAGE"4V"
PACKAGE"0805"
VALUE"47UF";
"2"
$PN"2"10;
"1"
$PN"1"7;
%"SOLDER_PREFORM"
"1","(-6150,2700)","0","mech","I39";
;
$LOCATION"SP3"
CDS_LOCATION"SP3"
$SEC"1"
CDS_SEC"1"
CDS_LIB"mech"
CDS_LMAN_SYM_OUTLINE"0,0,250,-200"
CLS_PN"G380-10015-01";
"2"
$PN"2"23;
"1"
$PN"1"11;
%"VCC"
"1","(-13250,3750)","0","cls","I43";
;
BODY_TYPE"PLUMBING"
CDS_LMAN_SYM_OUTLINE"-250,250,250,-250"
CDS_LIB"cls"
HDL_POWER"XP3R3V"
VOLTAGE"3.3";
"$PIN0"3;
%"RESISTOR"
"2","(-13200,3350)","0","passive","I44";
;
$LOCATION"R243"
CDS_LOCATION"R243"
$SEC"1"
CDS_SEC"1"
TOLERANCE"1%"
CDS_LMAN_SYM_OUTLINE"-50,50,50,-100"
CDS_LIB"passive"
CLS_PN"G155-14701-01"
VALUE"4.7KOHM"
PACKAGE"0402";
"1"
$PN"1"3;
"2"
$PN"2"6;
%"GND_SG"
"1","(-13100,4850)","0","cls","I45";
;
BODY_TYPE"PLUMBING"
CDS_LIB"cls"
CDS_LMAN_SYM_OUTLINE"0,0,100,-50"
HDL_POWER"SG";
"SGND"4;
%"CAPACITOR"
"2","(-13050,5250)","0","passive","I46";
;
$LOCATION"C255"
CDS_LOCATION"C255"
$SEC"1"
CDS_SEC"1"
TOLERANCE"10%"
CLS_PN"G105-0B104-EK"
CDS_LMAN_SYM_OUTLINE"-50,0,50,-50"
CDS_LIB"passive"
PACKAGE"0402"
VALUE"0.1UF"
VOLTAGE"25V";
"2"
$PN"2"4;
"1"
$PN"1"9;
%"VCC"
"1","(-13100,5950)","0","cls","I47";
;
BODY_TYPE"PLUMBING"
CDS_LMAN_SYM_OUTLINE"-250,250,250,-250"
CDS_LIB"cls"
HDL_POWER"XP12R0V"
VOLTAGE"12V";
"$PIN0"9;
%"FERRITEBEAD"
"1","(-12550,5550)","0","passive","I48";
;
$LOCATION"L9"
CDS_LOCATION"L9"
$SEC"1"
CDS_SEC"1"
CLS_PN"G191-10101-01"
TOLERANCE"25%"
CDS_LMAN_SYM_OUTLINE"0,0,200,-100"
CDS_LIB"passive"
VALUE"26OHM"
PACKAGE"0603";
"2"
$PN"2"18;
"1"
$PN"1"9;
%"CAPACITOR"
"1","(-11550,2600)","1","passive","I50";
;
$LOCATION"C258"
CDS_LOCATION"C258"
$SEC"1"
CDS_SEC"1"
TOLERANCE"10%"
CLS_PN"G104-0B103-EK"
CDS_LMAN_SYM_OUTLINE"0,50,50,-50"
CDS_LIB"passive"
VOLTAGE"25V"
VALUE"0.01UF"
PACKAGE"0402";
"2"
$PN"2"6;
"1"
$PN"1"1;
%"RESISTOR"
"2","(-12150,3850)","0","passive","I51";
;
$LOCATION"R246"
CDS_LOCATION"R246"
$SEC"1"
CDS_SEC"1"
TOLERANCE"1%"
CDS_LIB"passive"
CDS_LMAN_SYM_OUTLINE"-50,50,50,-100"
CLS_PN"A155-05101-DL"
NO_ASSY"TRUE"
VALUE"5.1KOHM"
PACKAGE"0402";
"1"
$PN"1"19;
"2"
$PN"2"8;
%"RESISTOR"
"2","(-12000,4950)","0","passive","I54";
;
$LOCATION"R247"
CDS_LOCATION"R247"
$SEC"1"
CDS_SEC"1"
TOLERANCE"1%"
CLS_PN"G155-11002-01"
CDS_LMAN_SYM_OUTLINE"-50,50,50,-100"
CDS_LIB"passive"
VALUE"10KOHM"
PACKAGE"0402"
NO_ASSY"TRUE";
"1"
$PN"1"18;
"2"
$PN"2"19;
%"RESISTOR"
"1","(-4600,2900)","1","passive","I56";
;
$LOCATION"R251"
CDS_LOCATION"R251"
$SEC"1"
CDS_SEC"1"
TOLERANCE"1%"
CLS_PN"G155-03322-01"
CDS_LIB"passive"
CDS_LMAN_SYM_OUTLINE"-50,50,100,-50"
VALUE"33.2KOHM"
PACKAGE"0402";
"1"
$PN"1"23;
"2"
$PN"2"15;
%"RESISTOR"
"1","(-4250,2900)","1","passive","I57";
;
$LOCATION"R252"
CDS_LOCATION"R252"
$SEC"1"
CDS_SEC"1"
TOLERANCE"-"
CLS_PN"G156-100R0-J0"
CDS_LMAN_SYM_OUTLINE"-50,50,100,-50"
CDS_LIB"passive"
VALUE"0OHM"
PACKAGE"0603"
NO_ASSY"TRUE";
"1"
$PN"1"23;
"2"
$PN"2"15;
%"GND_SG"
"1","(-11850,3300)","0","cls","I6";
;
BODY_TYPE"PLUMBING"
CDS_LIB"cls"
CDS_LMAN_SYM_OUTLINE"0,0,100,-50"
HDL_POWER"SG";
"SGND"8;
%"CAPACITOR"
"2","(-11800,3850)","0","passive","I7";
;
$LOCATION"C256"
CDS_LOCATION"C256"
$SEC"1"
CDS_SEC"1"
TOLERANCE"10%"
CLS_PN"G105-0B104-CK"
CDS_LIB"passive"
CDS_LMAN_SYM_OUTLINE"-50,0,50,-50"
PACKAGE"0402"
VOLTAGE"10V"
VALUE"0.1UF";
"2"
$PN"2"8;
"1"
$PN"1"19;
%"CAPACITOR"
"2","(-9850,2950)","0","passive","I9";
;
$LOCATION"C263"
CDS_LOCATION"C263"
$SEC"1"
CDS_SEC"1"
CLS_PN"G104-0B472-EK"
TOLERANCE"10%"
CDS_LMAN_SYM_OUTLINE"-50,0,50,-50"
CDS_LIB"passive"
VALUE"4700PF"
VOLTAGE"25V"
PACKAGE"0402";
"2"
$PN"2"13;
"1"
$PN"1"22;
%"VCC"
"1","(-450,4800)","0","cls","I97";
;
BODY_TYPE"PLUMBING"
CDS_LMAN_SYM_OUTLINE"-250,250,250,-250"
CDS_LIB"cls"
HDL_POWER"XP1R0V_FPGA"
VOLTAGE"1.0V";
"$PIN0"7;
END.
